FILE_TYPE = CONNECTIVITY;
{Allegro Design Entry HDL 17.2-2016 S081 (4005846) 1/11/2022}
"PAGE_NUMBER" = 83;
0"NC";
1"P3V3_AUX\g";
2"P3V3_AUX\g";
3"P12V_S3_AUX_CPU0_NVDIMM\g";
4"P12V_S3_AUX_CPU0_NVDIMM\g";
5"GND\g";
6"GND\g";
7"GND\g";
8"GND\g";
9"GND\g";
10"M_A_CPU0_SB_DQS_DP<9:0>";
11"M_A_CPU0_SB_DQS_DN<9:0>";
12"M_A_CPU0_SA_DQS_DP<9:0>";
13"M_A_CPU0_SA_DQS_DN<9:0>";
14"M_A_CPU0_SB_DQ<31:0>";
15"M_A_CPU0_SA_DQ<31:0>";
16"M_A_CPU0_SB_CB<7:0>";
17"M_A_CPU0_SA_CB<7:0>";
18"M_A_CPU0_SB_CA<6:0>";
19"M_A_CPU0_SA_CA<6:0>";
20"M_A_CPU0_ALERT_N";
21"I3C_SPD_DDRABCD_CPU0_LVC1_SCL_R2";
22"I3C_SPD_DDRABCD_CPU0_LVC1_SDA";
23"PD_CHA_CPU0_DIMM2_SAA";
24"RST_M_AB_CPU0_FPGA_N";
25"I3C_SPD_DDRABCD_CPU0_LVC1_SCL";
26"PWRGD_CHA_CPU0_DIMM2";
27"TP_CHA_CPU0_DIMM2_FRU_6";
28"TP_CHA_CPU0_DIMM2_FRU_2";
29"TP_CHA_CPU0_DIMM2_FRU_0";
30"M_A_CPU0_SB_DQ<24>";
31"M_A_CPU0_SB_DQS_DN<0>";
32"PD_CHA_CPU0_DIMM2_SAA";
33"M_A_CPU0_SB_RSP<1>";
34"M_A_CPU0_SA_RSP<1>";
35"M_A_CPU0_CLK_DP<1>";
36"M_A_CPU0_CLK_DN<1>";
37"M_A_CPU0_SB_CS_N<2>";
38"M_A_CPU0_SB_CS_N<3>";
39"M_A_CPU0_SA_CS_N<3>";
40"M_A_CPU0_SA_CS_N<2>";
41"M_A_CPU0_SB_PAR";
42"M_A_CPU0_SA_PAR";
43"M_A_CPU0_SA_DQ<31>";
44"M_A_CPU0_SA_CB<7>";
45"M_A_CPU0_SA_CB<4>";
46"M_A_CPU0_SA_CB<1>";
47"M_A_CPU0_SB_CB<7>";
48"M_A_CPU0_SA_CA<0>";
49"M_A_CPU0_SB_CA<0>";
50"M_A_CPU0_SA_CA<1>";
51"M_A_CPU0_SB_CA<1>";
52"M_A_CPU0_SA_CA<2>";
53"M_A_CPU0_SB_CA<2>";
54"M_A_CPU0_SA_CA<3>";
55"M_A_CPU0_SB_CA<3>";
56"M_A_CPU0_SA_CA<4>";
57"M_A_CPU0_SB_CA<4>";
58"M_A_CPU0_SA_CA<5>";
59"M_A_CPU0_SB_CA<5>";
60"M_A_CPU0_SA_CA<6>";
61"M_A_CPU0_SB_CA<6>";
62"M_A_CPU0_SA_CB<6>";
63"M_A_CPU0_SA_CB<5>";
64"M_A_CPU0_SA_CB<3>";
65"M_A_CPU0_SA_CB<2>";
66"M_A_CPU0_SA_CB<0>";
67"M_A_CPU0_SB_CB<6>";
68"M_A_CPU0_SB_CB<5>";
69"M_A_CPU0_SB_CB<4>";
70"M_A_CPU0_SB_CB<3>";
71"M_A_CPU0_SB_CB<2>";
72"M_A_CPU0_SB_CB<1>";
73"M_A_CPU0_SB_CB<0>";
74"M_A_CPU0_SA_DQ<30>";
75"M_A_CPU0_SA_DQ<29>";
76"M_A_CPU0_SA_DQ<28>";
77"M_A_CPU0_SA_DQ<27>";
78"M_A_CPU0_SA_DQ<26>";
79"M_A_CPU0_SA_DQ<25>";
80"M_A_CPU0_SA_DQ<24>";
81"M_A_CPU0_SA_DQ<23>";
82"M_A_CPU0_SA_DQ<22>";
83"M_A_CPU0_SA_DQ<21>";
84"M_A_CPU0_SA_DQ<20>";
85"M_A_CPU0_SA_DQ<19>";
86"M_A_CPU0_SA_DQ<18>";
87"M_A_CPU0_SA_DQ<17>";
88"M_A_CPU0_SA_DQ<16>";
89"M_A_CPU0_SA_DQ<15>";
90"M_A_CPU0_SA_DQ<14>";
91"M_A_CPU0_SA_DQ<13>";
92"M_A_CPU0_SA_DQ<12>";
93"M_A_CPU0_SA_DQ<11>";
94"M_A_CPU0_SA_DQ<10>";
95"M_A_CPU0_SA_DQ<9>";
96"M_A_CPU0_SA_DQ<8>";
97"M_A_CPU0_SA_DQ<7>";
98"M_A_CPU0_SA_DQ<6>";
99"M_A_CPU0_SA_DQ<5>";
100"M_A_CPU0_SA_DQ<4>";
101"M_A_CPU0_SA_DQ<3>";
102"M_A_CPU0_SA_DQ<2>";
103"M_A_CPU0_SA_DQ<1>";
104"M_A_CPU0_SA_DQ<0>";
105"M_A_CPU0_SB_DQ<31>";
106"M_A_CPU0_SB_DQ<30>";
107"M_A_CPU0_SB_DQ<29>";
108"M_A_CPU0_SB_DQ<28>";
109"M_A_CPU0_SB_DQ<27>";
110"M_A_CPU0_SB_DQ<26>";
111"M_A_CPU0_SB_DQ<25>";
112"M_A_CPU0_SB_DQ<23>";
113"M_A_CPU0_SB_DQ<22>";
114"M_A_CPU0_SB_DQ<21>";
115"M_A_CPU0_SB_DQ<20>";
116"M_A_CPU0_SB_DQ<19>";
117"M_A_CPU0_SB_DQ<18>";
118"M_A_CPU0_SB_DQ<17>";
119"M_A_CPU0_SB_DQ<16>";
120"M_A_CPU0_SB_DQ<15>";
121"M_A_CPU0_SB_DQ<14>";
122"M_A_CPU0_SB_DQ<13>";
123"M_A_CPU0_SB_DQ<12>";
124"M_A_CPU0_SB_DQ<11>";
125"M_A_CPU0_SB_DQ<10>";
126"M_A_CPU0_SB_DQ<9>";
127"M_A_CPU0_SB_DQ<8>";
128"M_A_CPU0_SB_DQ<7>";
129"M_A_CPU0_SB_DQ<6>";
130"M_A_CPU0_SB_DQ<5>";
131"M_A_CPU0_SB_DQ<4>";
132"M_A_CPU0_SB_DQ<3>";
133"M_A_CPU0_SB_DQ<2>";
134"M_A_CPU0_SB_DQ<1>";
135"M_A_CPU0_SB_DQ<0>";
136"TP_CHA_CPU0_DIMM2_FRU_5";
137"TP_CHA_CPU0_DIMM2_FRU_4";
138"TP_CHA_CPU0_DIMM2_FRU_3";
139"TP_CHA_CPU0_DIMM2_FRU_1";
140"M_A_CPU0_SA_DQS_DN<7>";
141"M_A_CPU0_SA_DQS_DP<6>";
142"M_A_CPU0_SB_DQS_DP<8>";
143"M_A_CPU0_SB_DQS_DN<8>";
144"M_A_CPU0_SB_DQS_DP<7>";
145"M_A_CPU0_SA_DQS_DN<0>";
146"M_A_CPU0_SA_DQS_DP<0>";
147"M_A_CPU0_SB_DQS_DP<0>";
148"M_A_CPU0_SA_DQS_DN<1>";
149"M_A_CPU0_SA_DQS_DP<1>";
150"M_A_CPU0_SB_DQS_DN<1>";
151"M_A_CPU0_SB_DQS_DP<1>";
152"M_A_CPU0_SA_DQS_DN<2>";
153"M_A_CPU0_SA_DQS_DP<2>";
154"M_A_CPU0_SB_DQS_DN<2>";
155"M_A_CPU0_SB_DQS_DP<2>";
156"M_A_CPU0_SA_DQS_DN<3>";
157"M_A_CPU0_SA_DQS_DP<3>";
158"M_A_CPU0_SB_DQS_DN<3>";
159"M_A_CPU0_SB_DQS_DP<3>";
160"M_A_CPU0_SA_DQS_DN<4>";
161"M_A_CPU0_SA_DQS_DP<4>";
162"M_A_CPU0_SB_DQS_DN<4>";
163"M_A_CPU0_SB_DQS_DP<4>";
164"M_A_CPU0_SA_DQS_DN<5>";
165"M_A_CPU0_SA_DQS_DP<5>";
166"M_A_CPU0_SB_DQS_DN<5>";
167"M_A_CPU0_SB_DQS_DP<5>";
168"M_A_CPU0_SA_DQS_DN<6>";
169"M_A_CPU0_SB_DQS_DN<6>";
170"M_A_CPU0_SB_DQS_DP<6>";
171"M_A_CPU0_SA_DQS_DP<7>";
172"M_A_CPU0_SB_DQS_DN<7>";
173"M_A_CPU0_SA_DQS_DN<8>";
174"M_A_CPU0_SA_DQS_DP<8>";
175"M_A_CPU0_SA_DQS_DN<9>";
176"M_A_CPU0_SA_DQS_DP<9>";
177"M_A_CPU0_SB_DQS_DN<9>";
178"M_A_CPU0_SB_DQS_DP<9>";
%"UNIVERSAL_GND"
"1","(-1425,-175)","0","logical_power","I1";
;
CDS_LIB"logical_power"
HDL_POWER"GND";
"A"5;
%"Q_RES"
"2","(-1425,50)","0","pure_quanta","I10";
;
PART_NUMBER"CS31542FB02"
PACK_TYPE"0402LF"
MATERIAL"CHIP"
TOLERANCE"1%"
VALUE"15.4K"
WATTAGE"1/16W"
$LOCATION"R27"
CDS_LIB"pure_quanta"
CDS_LOCATION"R27"
$SEC"1"
CDS_SEC"1";
"A"
$PN"1"32;
"B"
$PN"2"5;
%"TAP"
"1","(0,3550)","0","standard","I100";
;
CDS_LIB"standard"
BODY_TYPE"PLUMBING"
HDL_TAP"TRUE";
"B \NAC \NWC"15;
"S \NAC"
BN"18"86;
%"TAP"
"1","(0,3650)","0","standard","I101";
;
CDS_LIB"standard"
BODY_TYPE"PLUMBING"
HDL_TAP"TRUE";
"B \NAC \NWC"15;
"S \NAC"
BN"20"84;
%"TAP"
"1","(0,3700)","0","standard","I102";
;
CDS_LIB"standard"
BODY_TYPE"PLUMBING"
HDL_TAP"TRUE";
"B \NAC \NWC"15;
"S \NAC"
BN"21"83;
%"TAP"
"1","(0,3850)","0","standard","I103";
;
CDS_LIB"standard"
BODY_TYPE"PLUMBING"
HDL_TAP"TRUE";
"B \NAC \NWC"15;
"S \NAC"
BN"24"80;
%"TAP"
"1","(0,3800)","0","standard","I104";
;
CDS_LIB"standard"
BODY_TYPE"PLUMBING"
HDL_TAP"TRUE";
"B \NAC \NWC"15;
"S \NAC"
BN"23"81;
%"TAP"
"1","(0,3750)","0","standard","I105";
;
CDS_LIB"standard"
BODY_TYPE"PLUMBING"
HDL_TAP"TRUE";
"B \NAC \NWC"15;
"S \NAC"
BN"22"82;
%"TAP"
"1","(0,3950)","0","standard","I106";
;
CDS_LIB"standard"
BODY_TYPE"PLUMBING"
HDL_TAP"TRUE";
"B \NAC \NWC"15;
"S \NAC"
BN"26"78;
%"TAP"
"1","(0,3900)","0","standard","I107";
;
CDS_LIB"standard"
BODY_TYPE"PLUMBING"
HDL_TAP"TRUE";
"B \NAC \NWC"15;
"S \NAC"
BN"25"79;
%"TAP"
"1","(-1650,4050)","2","standard","I109";
;
CDS_LIB"standard"
BODY_TYPE"PLUMBING"
HDL_TAP"TRUE";
"B \NAC \NWC"19;
"S \NAC"
BN"3"54;
%"TAP"
"1","(-1650,4000)","2","standard","I110";
;
CDS_LIB"standard"
BODY_TYPE"PLUMBING"
HDL_TAP"TRUE";
"B \NAC \NWC"19;
"S \NAC"
BN"2"52;
%"TAP"
"1","(-1650,4100)","2","standard","I111";
;
CDS_LIB"standard"
BODY_TYPE"PLUMBING"
HDL_TAP"TRUE";
"B \NAC \NWC"19;
"S \NAC"
BN"4"56;
%"TAP"
"1","(-1650,4200)","2","standard","I112";
;
CDS_LIB"standard"
BODY_TYPE"PLUMBING"
HDL_TAP"TRUE";
"B \NAC \NWC"19;
"S \NAC"
BN"6"60;
%"TAP"
"1","(-1650,4150)","2","standard","I113";
;
CDS_LIB"standard"
BODY_TYPE"PLUMBING"
HDL_TAP"TRUE";
"B \NAC \NWC"19;
"S \NAC"
BN"5"58;
%"TAP"
"1","(0,4000)","0","standard","I114";
;
CDS_LIB"standard"
BODY_TYPE"PLUMBING"
HDL_TAP"TRUE";
"B \NAC \NWC"15;
"S \NAC"
BN"27"77;
%"TAP"
"1","(0,4050)","0","standard","I115";
;
CDS_LIB"standard"
BODY_TYPE"PLUMBING"
HDL_TAP"TRUE";
"B \NAC \NWC"15;
"S \NAC"
BN"28"76;
%"TAP"
"1","(0,4100)","0","standard","I116";
;
CDS_LIB"standard"
BODY_TYPE"PLUMBING"
HDL_TAP"TRUE";
"B \NAC \NWC"15;
"S \NAC"
BN"29"75;
%"TAP"
"1","(0,4200)","0","standard","I117";
;
CDS_LIB"standard"
BODY_TYPE"PLUMBING"
HDL_TAP"TRUE";
"B \NAC \NWC"15;
"S \NAC"
BN"31"43;
%"TAP"
"1","(0,4150)","0","standard","I118";
;
CDS_LIB"standard"
BODY_TYPE"PLUMBING"
HDL_TAP"TRUE";
"B \NAC \NWC"15;
"S \NAC"
BN"30"74;
%"VCC_CORE"
"1","(1725,650)","0","logical_power","I119";
;
HDL_POWER"P3V3_AUX"
CDS_LIB"logical_power";
"A"2;
%"Q_CAP"
"1","(1725,325)","0","pure_quanta","I120";
;
PART_NUMBER"CH5221MEB00"
PACK_TYPE"C0402"
VOLTAGE"6.3V"
MATERIAL"X6S"
VALUE"2.2UF"
TOLERANCE"20%"
$LOCATION"C5"
CDS_LIB"pure_quanta"
CDS_LOCATION"C5"
$SEC"1"
CDS_SEC"1";
"B"
$PN"2"6;
"A"
$PN"1"2;
%"UNIVERSAL_GND"
"1","(1725,-50)","0","logical_power","I121";
;
CDS_LIB"logical_power"
HDL_POWER"GND";
"A"6;
%"Q_CAP"
"1","(2725,325)","0","pure_quanta","I122";
;
PART_NUMBER"CH6103KEA00"
MATERIAL"X6S"
TOLERANCE"10%"
VALUE"10UF"
PACK_TYPE"C0805"
VOLTAGE"16V"
$LOCATION"C6"
CDS_LIB"pure_quanta"
CDS_LOCATION"C6"
$SEC"1"
CDS_SEC"1";
"B"
$PN"2"7;
"A"
$PN"1"3;
%"VCC_CORE"
"1","(2725,650)","0","logical_power","I123";
;
HDL_POWER"P12V_S3_AUX_CPU0_NVDIMM"
CDS_LIB"logical_power";
"A"3;
%"TAP"
"1","(2725,2250)","0","standard","I126";
;
CDS_LIB"standard"
BODY_TYPE"PLUMBING"
HDL_TAP"TRUE";
"B \NAC \NWC"10;
"S \NAC"
BN"0"147;
%"TAP"
"1","(2725,2450)","0","standard","I127";
;
CDS_LIB"standard"
BODY_TYPE"PLUMBING"
HDL_TAP"TRUE";
"B \NAC \NWC"10;
"S \NAC"
BN"2"155;
%"TAP"
"1","(2725,2350)","0","standard","I128";
;
CDS_LIB"standard"
BODY_TYPE"PLUMBING"
HDL_TAP"TRUE";
"B \NAC \NWC"10;
"S \NAC"
BN"1"151;
%"TAP"
"1","(2725,2550)","0","standard","I129";
;
CDS_LIB"standard"
BODY_TYPE"PLUMBING"
HDL_TAP"TRUE";
"B \NAC \NWC"10;
"S \NAC"
BN"3"159;
%"VCC_CORE"
"1","(-2475,2075)","0","logical_power","I13";
;
HDL_POWER"P3V3_AUX"
CDS_LIB"logical_power";
"A"1;
%"TAP"
"1","(2725,2650)","0","standard","I130";
;
CDS_LIB"standard"
BODY_TYPE"PLUMBING"
HDL_TAP"TRUE";
"B \NAC \NWC"10;
"S \NAC"
BN"4"163;
%"TAP"
"1","(2725,2750)","0","standard","I131";
;
CDS_LIB"standard"
BODY_TYPE"PLUMBING"
HDL_TAP"TRUE";
"B \NAC \NWC"10;
"S \NAC"
BN"5"167;
%"TAP"
"1","(2725,2950)","0","standard","I132";
;
CDS_LIB"standard"
BODY_TYPE"PLUMBING"
HDL_TAP"TRUE";
"B \NAC \NWC"10;
"S \NAC"
BN"7"144;
%"TAP"
"1","(2725,2850)","0","standard","I133";
;
CDS_LIB"standard"
BODY_TYPE"PLUMBING"
HDL_TAP"TRUE";
"B \NAC \NWC"10;
"S \NAC"
BN"6"170;
%"TAP"
"1","(2725,3050)","0","standard","I134";
;
CDS_LIB"standard"
BODY_TYPE"PLUMBING"
HDL_TAP"TRUE";
"B \NAC \NWC"10;
"S \NAC"
BN"8"142;
%"TAP"
"1","(2725,3150)","0","standard","I135";
;
CDS_LIB"standard"
BODY_TYPE"PLUMBING"
HDL_TAP"TRUE";
"B \NAC \NWC"10;
"S \NAC"
BN"9"178;
%"TAP"
"1","(2725,3300)","0","standard","I136";
;
CDS_LIB"standard"
BODY_TYPE"PLUMBING"
HDL_TAP"TRUE";
"B \NAC \NWC"12;
"S \NAC"
BN"0"146;
%"TAP"
"1","(2725,3400)","0","standard","I137";
;
CDS_LIB"standard"
BODY_TYPE"PLUMBING"
HDL_TAP"TRUE";
"B \NAC \NWC"12;
"S \NAC"
BN"1"149;
%"TAP"
"1","(2725,3500)","0","standard","I138";
;
CDS_LIB"standard"
BODY_TYPE"PLUMBING"
HDL_TAP"TRUE";
"B \NAC \NWC"12;
"S \NAC"
BN"2"153;
%"TAP"
"1","(2725,3600)","0","standard","I139";
;
CDS_LIB"standard"
BODY_TYPE"PLUMBING"
HDL_TAP"TRUE";
"B \NAC \NWC"12;
"S \NAC"
BN"3"157;
%"TAP"
"1","(2725,3700)","0","standard","I140";
;
CDS_LIB"standard"
BODY_TYPE"PLUMBING"
HDL_TAP"TRUE";
"B \NAC \NWC"12;
"S \NAC"
BN"4"161;
%"TAP"
"1","(2725,3800)","0","standard","I141";
;
CDS_LIB"standard"
BODY_TYPE"PLUMBING"
HDL_TAP"TRUE";
"B \NAC \NWC"12;
"S \NAC"
BN"5"165;
%"TAP"
"1","(2725,3900)","0","standard","I142";
;
CDS_LIB"standard"
BODY_TYPE"PLUMBING"
HDL_TAP"TRUE";
"B \NAC \NWC"12;
"S \NAC"
BN"6"141;
%"UNIVERSAL_GND"
"1","(3350,-50)","0","logical_power","I143";
;
CDS_LIB"logical_power"
HDL_POWER"GND";
"A"7;
%"Q_CAP"
"1","(3350,325)","0","pure_quanta","I144";
;
PART_NUMBER"CH6103KEA00"
MATERIAL"X6S"
TOLERANCE"10%"
VALUE"10UF"
PACK_TYPE"C0805"
VOLTAGE"16V"
$LOCATION"C7"
CDS_LIB"pure_quanta"
CDS_LOCATION"C7"
$SEC"1"
CDS_SEC"1";
"B"
$PN"2"7;
"A"
$PN"1"3;
%"UNIVERSAL_GND"
"1","(4350,500)","0","logical_power","I145";
;
CDS_LIB"logical_power"
HDL_POWER"GND";
"A"9;
%"TAP"
"1","(2900,2200)","0","standard","I147";
;
CDS_LIB"standard"
BODY_TYPE"PLUMBING"
HDL_TAP"TRUE";
"B \NAC \NWC"11;
"S \NAC"
BN"0"31;
%"TAP"
"1","(2900,2300)","0","standard","I148";
;
CDS_LIB"standard"
BODY_TYPE"PLUMBING"
HDL_TAP"TRUE";
"B \NAC \NWC"11;
"S \NAC"
BN"1"150;
%"TAP"
"1","(2900,2400)","0","standard","I149";
;
CDS_LIB"standard"
BODY_TYPE"PLUMBING"
HDL_TAP"TRUE";
"B \NAC \NWC"11;
"S \NAC"
BN"2"154;
%"TAP"
"1","(2900,2500)","0","standard","I150";
;
CDS_LIB"standard"
BODY_TYPE"PLUMBING"
HDL_TAP"TRUE";
"B \NAC \NWC"11;
"S \NAC"
BN"3"158;
%"TAP"
"1","(2900,2700)","0","standard","I151";
;
CDS_LIB"standard"
BODY_TYPE"PLUMBING"
HDL_TAP"TRUE";
"B \NAC \NWC"11;
"S \NAC"
BN"5"166;
%"TAP"
"1","(2900,2600)","0","standard","I152";
;
CDS_LIB"standard"
BODY_TYPE"PLUMBING"
HDL_TAP"TRUE";
"B \NAC \NWC"11;
"S \NAC"
BN"4"162;
%"TAP"
"1","(2900,2800)","0","standard","I153";
;
CDS_LIB"standard"
BODY_TYPE"PLUMBING"
HDL_TAP"TRUE";
"B \NAC \NWC"11;
"S \NAC"
BN"6"169;
%"TAP"
"1","(2900,2900)","0","standard","I154";
;
CDS_LIB"standard"
BODY_TYPE"PLUMBING"
HDL_TAP"TRUE";
"B \NAC \NWC"11;
"S \NAC"
BN"7"172;
%"TAP"
"1","(2900,3000)","0","standard","I155";
;
CDS_LIB"standard"
BODY_TYPE"PLUMBING"
HDL_TAP"TRUE";
"B \NAC \NWC"11;
"S \NAC"
BN"8"143;
%"TAP"
"1","(2900,3100)","0","standard","I156";
;
CDS_LIB"standard"
BODY_TYPE"PLUMBING"
HDL_TAP"TRUE";
"B \NAC \NWC"11;
"S \NAC"
BN"9"177;
%"TAP"
"1","(2900,3250)","0","standard","I157";
;
CDS_LIB"standard"
BODY_TYPE"PLUMBING"
HDL_TAP"TRUE";
"B \NAC \NWC"13;
"S \NAC"
BN"0"145;
%"TAP"
"1","(2900,3350)","0","standard","I158";
;
CDS_LIB"standard"
BODY_TYPE"PLUMBING"
HDL_TAP"TRUE";
"B \NAC \NWC"13;
"S \NAC"
BN"1"148;
%"TAP"
"1","(2900,3450)","0","standard","I159";
;
CDS_LIB"standard"
BODY_TYPE"PLUMBING"
HDL_TAP"TRUE";
"B \NAC \NWC"13;
"S \NAC"
BN"2"152;
%"TAP"
"1","(2900,3550)","0","standard","I160";
;
CDS_LIB"standard"
BODY_TYPE"PLUMBING"
HDL_TAP"TRUE";
"B \NAC \NWC"13;
"S \NAC"
BN"3"156;
%"TAP"
"1","(2900,3650)","0","standard","I161";
;
CDS_LIB"standard"
BODY_TYPE"PLUMBING"
HDL_TAP"TRUE";
"B \NAC \NWC"13;
"S \NAC"
BN"4"160;
%"TAP"
"1","(2900,3750)","0","standard","I162";
;
CDS_LIB"standard"
BODY_TYPE"PLUMBING"
HDL_TAP"TRUE";
"B \NAC \NWC"13;
"S \NAC"
BN"5"164;
%"TAP"
"1","(2900,3850)","0","standard","I163";
;
CDS_LIB"standard"
BODY_TYPE"PLUMBING"
HDL_TAP"TRUE";
"B \NAC \NWC"13;
"S \NAC"
BN"6"168;
%"TAP"
"1","(2900,3950)","0","standard","I164";
;
CDS_LIB"standard"
BODY_TYPE"PLUMBING"
HDL_TAP"TRUE";
"B \NAC \NWC"13;
"S \NAC"
BN"7"140;
%"TAP"
"1","(2725,4000)","0","standard","I168";
;
CDS_LIB"standard"
BODY_TYPE"PLUMBING"
HDL_TAP"TRUE";
"B \NAC \NWC"12;
"S \NAC"
BN"7"171;
%"TAP"
"1","(2725,4100)","0","standard","I169";
;
CDS_LIB"standard"
BODY_TYPE"PLUMBING"
HDL_TAP"TRUE";
"B \NAC \NWC"12;
"S \NAC"
BN"8"174;
%"TAP"
"1","(2725,4200)","0","standard","I170";
;
CDS_LIB"standard"
BODY_TYPE"PLUMBING"
HDL_TAP"TRUE";
"B \NAC \NWC"12;
"S \NAC"
BN"9"176;
%"TAP"
"1","(2900,4050)","0","standard","I171";
;
CDS_LIB"standard"
BODY_TYPE"PLUMBING"
HDL_TAP"TRUE";
"B \NAC \NWC"13;
"S \NAC"
BN"8"173;
%"TAP"
"1","(2900,4150)","0","standard","I172";
;
CDS_LIB"standard"
BODY_TYPE"PLUMBING"
HDL_TAP"TRUE";
"B \NAC \NWC"13;
"S \NAC"
BN"9"175;
%"VCC_CORE"
"1","(4350,4750)","0","logical_power","I175";
;
HDL_POWER"P12V_S3_AUX_CPU0_NVDIMM"
CDS_LIB"logical_power";
"A"4;
%"UNIVERSAL_GND"
"1","(6050,500)","0","logical_power","I176";
;
CDS_LIB"logical_power"
HDL_POWER"GND";
"A"8;
%"SCONN288_ADR50017P087CC"
"1","(-825,2475)","0","pure_quanta","I177";
;
PART_NUMBER"DFHST8FS460"
VALUE"SCONN288_ADR50017-P087CC"
PART_TYPE"SMLF"
MATERIAL"IO"
$LOCATION"J2"
CDS_LIB"pure_quanta"
CDS_LMAN_SYM_OUTLINE"-450,1875,450,-1875"
NEEDS_NO_SIZE"TRUE"
CDS_LOCATION"J2"
$SEC"1"
CDS_SEC"1";
"DQ31_A"
$PN"194"43;
"CB7_A"
$PN"205"44;
"CB4_A"
$PN"58"45;
"CB1_A"
$PN"53"46;
"CB7_B"
$PN"236"47;
"ALERT_N \B"
$PN"62"20;
"CA0_A"
$PN"66"48;
"CA0_B"
$PN"76"49;
"CA1_A"
$PN"211"50;
"CA1_B"
$PN"221"51;
"CA2_A"
$PN"68"52;
"CA2_B"
$PN"78"53;
"CA3_A"
$PN"213"54;
"CA3_B"
$PN"223"55;
"CA4_A"
$PN"70"56;
"CA4_B"
$PN"80"57;
"CA5_A"
$PN"215"58;
"CA5_B"
$PN"225"59;
"CA6_A"
$PN"72"60;
"CA6_B"
$PN"82"61;
"CB6_A"
$PN"203"62;
"CB5_A"
$PN"60"63;
"CB3_A"
$PN"198"64;
"CB2_A"
$PN"196"65;
"CB0_A"
$PN"51"66;
"CB6_B"
$PN"234"67;
"CB5_B"
$PN"91"68;
"CB4_B"
$PN"89"69;
"CB3_B"
$PN"243"70;
"CB2_B"
$PN"241"71;
"CB1_B"
$PN"98"72;
"CB0_B"
$PN"96"73;
"CK_C \B"
$PN"218"36;
"CK_T"
$PN"217"35;
"CS0_A_N"
$PN"64"40;
"CS0_B_N"
$PN"84"37;
"CS1_A_N"
$PN"209"39;
"CS1_B_N"
$PN"229"38;
"DQ30_A"
$PN"192"74;
"DQ29_A"
$PN"49"75;
"DQ28_A"
$PN"47"76;
"DQ27_A"
$PN"187"77;
"DQ26_A"
$PN"185"78;
"DQ25_A"
$PN"42"79;
"DQ24_A"
$PN"40"80;
"DQ23_A"
$PN"183"81;
"DQ22_A"
$PN"181"82;
"DQ21_A"
$PN"38"83;
"DQ20_A"
$PN"36"84;
"DQ19_A"
$PN"176"85;
"DQ18_A"
$PN"174"86;
"DQ17_A"
$PN"31"87;
"DQ16_A"
$PN"29"88;
"DQ15_A"
$PN"172"89;
"DQ14_A"
$PN"170"90;
"DQ13_A"
$PN"27"91;
"DQ12_A"
$PN"25"92;
"DQ11_A"
$PN"165"93;
"DQ10_A"
$PN"163"94;
"DQ9_A"
$PN"20"95;
"DQ8_A"
$PN"18"96;
"DQ7_A"
$PN"161"97;
"DQ6_A"
$PN"159"98;
"DQ5_A"
$PN"16"99;
"DQ4_A"
$PN"14"100;
"DQ3_A"
$PN"154"101;
"DQ2_A"
$PN"152"102;
"DQ1_A"
$PN"9"103;
"DQ0_A"
$PN"7"104;
"DQ31_B"
$PN"287"105;
"DQ30_B"
$PN"285"106;
"DQ29_B"
$PN"142"107;
"DQ28_B"
$PN"140"108;
"DQ27_B"
$PN"280"109;
"DQ26_B"
$PN"278"110;
"DQ25_B"
$PN"135"111;
"DQ24_B"
$PN"133"30;
"DQ23_B"
$PN"276"112;
"DQ22_B"
$PN"274"113;
"DQ21_B"
$PN"131"114;
"DQ20_B"
$PN"129"115;
"DQ19_B"
$PN"269"116;
"DQ18_B"
$PN"267"117;
"DQ17_B"
$PN"124"118;
"DQ16_B"
$PN"122"119;
"DQ15_B"
$PN"265"120;
"DQ14_B"
$PN"263"121;
"DQ13_B"
$PN"120"122;
"DQ12_B"
$PN"118"123;
"DQ11_B"
$PN"258"124;
"DQ10_B"
$PN"256"125;
"DQ9_B"
$PN"113"126;
"DQ8_B"
$PN"111"127;
"DQ7_B"
$PN"254"128;
"DQ6_B"
$PN"252"129;
"DQ5_B"
$PN"109"130;
"DQ4_B"
$PN"107"131;
"DQ3_B"
$PN"247"132;
"DQ2_B"
$PN"245"133;
"DQ1_B"
$PN"102"134;
"DQ0_B"
$PN"100"135;
"HSA"
$PN"148"23;
"HSCL"
$PN"4"21;
"HSDA"
$PN"5"22;
"LBD||RSP_A_N"
$PN"86"34;
"LBS||RSP_B_N"
$PN"87"33;
"PAR_A"
$PN"74"42;
"PAR_B"
$PN"227"41;
"PWR_GOOD||FAIL_N"
$PN"147"26;
"RESET_N \B"
$PN"207"24;
"RFU6"
$PN"232"27;
"RFU5"
$PN"231"136;
"RFU4"
$PN"220"137;
"RFU3"
$PN"150"138;
"RFU2"
$PN"149"28;
"RFU1"
$PN"144"139;
"RFU0"
$PN"2"29;
"VIN_MGMT"
$PN"3"1;
%"SCONN288_ADR50017P087CC"
"3","(5200,2575)","0","pure_quanta","I179";
;
PART_NUMBER"DFHST8FS460"
MATERIAL"IO"
PART_TYPE"SMLF"
VALUE"SCONN288_ADR50017-P087CC"
$LOCATION"J2"
NEEDS_NO_SIZE"TRUE"
CDS_LMAN_SYM_OUTLINE"-450,1775,450,-1775"
CDS_LIB"pure_quanta"
CDS_LOCATION"J2"
$SEC"3"
CDS_SEC"3";
"G3"
$PN"G3"8;
"G2"
$PN"G2"8;
"G1"
$PN"G1"8;
"VSS62"
$PN"141"8;
"VSS61"
$PN"139"8;
"VSS60"
$PN"136"8;
"VSS58"
$PN"132"8;
"VSS104"
$PN"240"9;
"VSS102"
$PN"235"9;
"VSS100"
$PN"230"9;
"VIN_BULK2"
$PN"146"4;
"VIN_BULK1"
$PN"145"4;
"VIN_BULK0"
$PN"1"4;
"VSS126"
$PN"288"9;
"VSS125"
$PN"286"9;
"VSS124"
$PN"284"9;
"VSS123"
$PN"281"9;
"VSS122"
$PN"279"9;
"VSS121"
$PN"277"9;
"VSS120"
$PN"275"9;
"VSS119"
$PN"273"9;
"VSS118"
$PN"270"9;
"VSS117"
$PN"268"9;
"VSS116"
$PN"266"9;
"VSS115"
$PN"264"9;
"VSS114"
$PN"262"9;
"VSS113"
$PN"259"9;
"VSS112"
$PN"257"9;
"VSS111"
$PN"255"9;
"VSS110"
$PN"253"9;
"VSS109"
$PN"251"9;
"VSS108"
$PN"248"9;
"VSS107"
$PN"246"9;
"VSS106"
$PN"244"9;
"VSS105"
$PN"242"9;
"VSS103"
$PN"237"9;
"VSS101"
$PN"233"9;
"VSS99"
$PN"228"9;
"VSS98"
$PN"226"9;
"VSS97"
$PN"224"9;
"VSS96"
$PN"222"9;
"VSS95"
$PN"219"9;
"VSS94"
$PN"216"9;
"VSS93"
$PN"214"9;
"VSS92"
$PN"212"9;
"VSS91"
$PN"210"9;
"VSS90"
$PN"208"9;
"VSS89"
$PN"206"9;
"VSS88"
$PN"204"9;
"VSS87"
$PN"202"9;
"VSS86"
$PN"199"9;
"VSS85"
$PN"197"9;
"VSS84"
$PN"195"9;
"VSS83"
$PN"193"9;
"VSS82"
$PN"191"9;
"VSS81"
$PN"188"9;
"VSS80"
$PN"186"9;
"VSS79"
$PN"184"9;
"VSS78"
$PN"182"9;
"VSS77"
$PN"180"9;
"VSS76"
$PN"177"9;
"VSS75"
$PN"175"9;
"VSS74"
$PN"173"9;
"VSS73"
$PN"171"9;
"VSS72"
$PN"169"9;
"VSS71"
$PN"166"9;
"VSS70"
$PN"164"9;
"VSS69"
$PN"162"9;
"VSS68"
$PN"160"9;
"VSS67"
$PN"158"9;
"VSS66"
$PN"155"9;
"VSS65"
$PN"153"9;
"VSS64"
$PN"151"9;
"VSS63"
$PN"143"8;
"VSS59"
$PN"134"8;
"VSS57"
$PN"130"8;
"VSS56"
$PN"128"8;
"VSS55"
$PN"125"8;
"VSS54"
$PN"123"8;
"VSS53"
$PN"121"8;
"VSS52"
$PN"119"8;
"VSS51"
$PN"117"8;
"VSS50"
$PN"114"8;
"VSS49"
$PN"112"8;
"VSS48"
$PN"110"8;
"VSS47"
$PN"108"8;
"VSS46"
$PN"106"8;
"VSS45"
$PN"103"8;
"VSS44"
$PN"101"8;
"VSS43"
$PN"99"8;
"VSS42"
$PN"97"8;
"VSS41"
$PN"95"8;
"VSS40"
$PN"92"8;
"VSS39"
$PN"90"8;
"VSS38"
$PN"88"8;
"VSS37"
$PN"85"8;
"VSS36"
$PN"83"8;
"VSS35"
$PN"81"8;
"VSS34"
$PN"79"8;
"VSS33"
$PN"77"8;
"VSS32"
$PN"75"8;
"VSS31"
$PN"73"8;
"VSS30"
$PN"71"8;
"VSS29"
$PN"69"8;
"VSS28"
$PN"67"8;
"VSS27"
$PN"65"8;
"VSS26"
$PN"63"8;
"VSS25"
$PN"61"8;
"VSS24"
$PN"59"8;
"VSS23"
$PN"57"8;
"VSS22"
$PN"54"8;
"VSS21"
$PN"52"8;
"VSS20"
$PN"50"8;
"VSS19"
$PN"48"8;
"VSS18"
$PN"46"8;
"VSS17"
$PN"43"8;
"VSS16"
$PN"41"8;
"VSS15"
$PN"39"8;
"VSS14"
$PN"37"8;
"VSS13"
$PN"35"8;
"VSS12"
$PN"32"8;
"VSS11"
$PN"30"8;
"VSS10"
$PN"28"8;
"VSS9"
$PN"26"8;
"VSS8"
$PN"24"8;
"VSS7"
$PN"21"8;
"VSS6"
$PN"19"8;
"VSS5"
$PN"17"8;
"VSS4"
$PN"15"8;
"VSS3"
$PN"13"8;
"VSS2"
$PN"10"8;
"VSS1"
$PN"8"8;
"VSS0"
$PN"6"8;
%"SCONN288_ADR50017P087CC"
"2","(1825,3200)","0","pure_quanta","I181";
;
PART_NUMBER"DFHST8FS460"
MATERIAL"IO"
PART_TYPE"SMLF"
VALUE"SCONN288_ADR50017-P087CC"
LOCATION"J2"
CDS_LIB"pure_quanta"
NEEDS_NO_SIZE"TRUE"
CDS_LMAN_SYM_OUTLINE"-600,1150,600,-1150"
$SEC"2"
CDS_SEC"2";
"DQS7_A_C||TDQS7_A_C \B"
$PN"178"140;
"DQS6_A_T||TDQS6_A_T"
$PN"168"141;
"DQS8_B_T||TDQS8_B_T"
$PN"283"142;
"DQS8_B_C||TDQS8_B_C \B"
$PN"282"143;
"DQS7_B_T||TDQS7_B_T"
$PN"272"144;
"DQS0_A_C \B"
$PN"12"145;
"DQS0_A_T"
$PN"11"146;
"DQS0_B_C \B"
$PN"105"31;
"DQS0_B_T"
$PN"104"147;
"DQS1_A_C \B"
$PN"23"148;
"DQS1_A_T"
$PN"22"149;
"DQS1_B_C \B"
$PN"116"150;
"DQS1_B_T"
$PN"115"151;
"DQS2_A_C \B"
$PN"34"152;
"DQS2_A_T"
$PN"33"153;
"DQS2_B_C \B"
$PN"127"154;
"DQS2_B_T"
$PN"126"155;
"DQS3_A_C \B"
$PN"45"156;
"DQS3_A_T"
$PN"44"157;
"DQS3_B_C \B"
$PN"138"158;
"DQS3_B_T"
$PN"137"159;
"DQS4_A_C \B"
$PN"56"160;
"DQS4_A_T"
$PN"55"161;
"DQS4_B_C \B"
$PN"238"162;
"DQS4_B_T"
$PN"239"163;
"DQS5_A_C||TDQS5_A_C||DQS5_A_T||TDQS5_A_T \B"
$PN"156"164;
"DQS5_A_T||TDQS5_A_T"
$PN"157"165;
"DQS5_B_C||TDQS5_B_C \B"
$PN"249"166;
"DQS5_B_T||TDQS5_B_T"
$PN"250"167;
"DQS6_A_C||TDQS6_A_C||DQS6_A_T||TDQS6_A_T \B"
$PN"167"168;
"DQS6_B_C||TDQS6_B_C \B"
$PN"260"169;
"DQS6_B_T||TDQS6_B_T"
$PN"261"170;
"DQS7_A_T||TDQS7_A_T"
$PN"179"171;
"DQS7_B_C||TDQS7_B_C \B"
$PN"271"172;
"DQS8_A_C||TDQS8_A_C \B"
$PN"189"173;
"DQS8_A_T||TDQS8_A_T"
$PN"190"174;
"DQS9_A_C||TDQS9_A_C \B"
$PN"200"175;
"DQS9_A_T||TDQS9_A_T"
$PN"201"176;
"DQS9_B_C||TDQS9_B_C \B"
$PN"94"177;
"DQS9_B_T||TDQS9_B_T||DBI4_B_N"
$PN"93"178;
%"Q_RES"
"1","(-2650,1500)","0","pure_quanta","I182";
;
PART_NUMBER"CS04992FB07"
VALUE"49.9"
MATERIAL"CHIP"
$LOCATION"R3876"
CDS_LIB"pure_quanta"
PACK_TYPE"0402LF"
TOLERANCE"1%"
WATTAGE"1/16W"
CDS_LOCATION"R3876"
$SEC"1"
CDS_SEC"1";
"B"
$PN"2"25;
"A"
$PN"1"21;
%"TAP"
"1","(-1650,2050)","2","standard","I24";
;
CDS_LIB"standard"
BODY_TYPE"PLUMBING"
HDL_TAP"TRUE";
"B \NAC \NWC"16;
"S \NAC"
BN"1"72;
%"TAP"
"1","(-1650,2000)","2","standard","I25";
;
CDS_LIB"standard"
BODY_TYPE"PLUMBING"
HDL_TAP"TRUE";
"B \NAC \NWC"16;
"S \NAC"
BN"0"73;
%"TAP"
"1","(-1650,2100)","2","standard","I26";
;
CDS_LIB"standard"
BODY_TYPE"PLUMBING"
HDL_TAP"TRUE";
"B \NAC \NWC"16;
"S \NAC"
BN"2"71;
%"TAP"
"1","(-1650,2150)","2","standard","I27";
;
CDS_LIB"standard"
BODY_TYPE"PLUMBING"
HDL_TAP"TRUE";
"B \NAC \NWC"16;
"S \NAC"
BN"3"70;
%"TAP"
"1","(-1650,2200)","2","standard","I28";
;
CDS_LIB"standard"
BODY_TYPE"PLUMBING"
HDL_TAP"TRUE";
"B \NAC \NWC"16;
"S \NAC"
BN"4"69;
%"TAP"
"1","(-1650,2300)","2","standard","I29";
;
CDS_LIB"standard"
BODY_TYPE"PLUMBING"
HDL_TAP"TRUE";
"B \NAC \NWC"16;
"S \NAC"
BN"6"67;
%"TAP"
"1","(-1650,2250)","2","standard","I30";
;
CDS_LIB"standard"
BODY_TYPE"PLUMBING"
HDL_TAP"TRUE";
"B \NAC \NWC"16;
"S \NAC"
BN"5"68;
%"TAP"
"1","(-1650,2450)","2","standard","I31";
;
CDS_LIB"standard"
BODY_TYPE"PLUMBING"
HDL_TAP"TRUE";
"B \NAC \NWC"17;
"S \NAC"
BN"0"66;
%"TAP"
"1","(-1650,2350)","2","standard","I32";
;
CDS_LIB"standard"
BODY_TYPE"PLUMBING"
HDL_TAP"TRUE";
"B \NAC \NWC"16;
"S \NAC"
BN"7"47;
%"TAP"
"1","(-1650,2500)","2","standard","I33";
;
CDS_LIB"standard"
BODY_TYPE"PLUMBING"
HDL_TAP"TRUE";
"B \NAC \NWC"17;
"S \NAC"
BN"1"46;
%"TAP"
"1","(-1650,2550)","2","standard","I34";
;
CDS_LIB"standard"
BODY_TYPE"PLUMBING"
HDL_TAP"TRUE";
"B \NAC \NWC"17;
"S \NAC"
BN"2"65;
%"TAP"
"1","(-1650,2650)","2","standard","I35";
;
CDS_LIB"standard"
BODY_TYPE"PLUMBING"
HDL_TAP"TRUE";
"B \NAC \NWC"17;
"S \NAC"
BN"4"45;
%"TAP"
"1","(-1650,2600)","2","standard","I36";
;
CDS_LIB"standard"
BODY_TYPE"PLUMBING"
HDL_TAP"TRUE";
"B \NAC \NWC"17;
"S \NAC"
BN"3"64;
%"TAP"
"1","(-1650,2700)","2","standard","I37";
;
CDS_LIB"standard"
BODY_TYPE"PLUMBING"
HDL_TAP"TRUE";
"B \NAC \NWC"17;
"S \NAC"
BN"5"63;
%"TAP"
"1","(-1650,2800)","2","standard","I38";
;
CDS_LIB"standard"
BODY_TYPE"PLUMBING"
HDL_TAP"TRUE";
"B \NAC \NWC"17;
"S \NAC"
BN"7"44;
%"TAP"
"1","(-1650,2750)","2","standard","I39";
;
CDS_LIB"standard"
BODY_TYPE"PLUMBING"
HDL_TAP"TRUE";
"B \NAC \NWC"17;
"S \NAC"
BN"6"62;
%"TAP"
"1","(-1650,3550)","2","standard","I40";
;
CDS_LIB"standard"
BODY_TYPE"PLUMBING"
HDL_TAP"TRUE";
"B \NAC \NWC"18;
"S \NAC"
BN"1"51;
%"TAP"
"1","(-1650,3600)","2","standard","I41";
;
CDS_LIB"standard"
BODY_TYPE"PLUMBING"
HDL_TAP"TRUE";
"B \NAC \NWC"18;
"S \NAC"
BN"2"53;
%"TAP"
"1","(-1650,3500)","2","standard","I42";
;
CDS_LIB"standard"
BODY_TYPE"PLUMBING"
HDL_TAP"TRUE";
"B \NAC \NWC"18;
"S \NAC"
BN"0"49;
%"TAP"
"1","(-1650,3650)","2","standard","I43";
;
CDS_LIB"standard"
BODY_TYPE"PLUMBING"
HDL_TAP"TRUE";
"B \NAC \NWC"18;
"S \NAC"
BN"3"55;
%"TAP"
"1","(-1650,3700)","2","standard","I44";
;
CDS_LIB"standard"
BODY_TYPE"PLUMBING"
HDL_TAP"TRUE";
"B \NAC \NWC"18;
"S \NAC"
BN"4"57;
%"TAP"
"1","(-1650,3750)","2","standard","I45";
;
CDS_LIB"standard"
BODY_TYPE"PLUMBING"
HDL_TAP"TRUE";
"B \NAC \NWC"18;
"S \NAC"
BN"5"59;
%"TAP"
"1","(-1650,3800)","2","standard","I46";
;
CDS_LIB"standard"
BODY_TYPE"PLUMBING"
HDL_TAP"TRUE";
"B \NAC \NWC"18;
"S \NAC"
BN"6"61;
%"TAP"
"1","(-1650,3900)","2","standard","I47";
;
CDS_LIB"standard"
BODY_TYPE"PLUMBING"
HDL_TAP"TRUE";
"B \NAC \NWC"19;
"S \NAC"
BN"0"48;
%"TAP"
"1","(-1650,3950)","2","standard","I48";
;
CDS_LIB"standard"
BODY_TYPE"PLUMBING"
HDL_TAP"TRUE";
"B \NAC \NWC"19;
"S \NAC"
BN"1"50;
%"TAP"
"1","(0,1000)","0","standard","I49";
;
CDS_LIB"standard"
BODY_TYPE"PLUMBING"
HDL_TAP"TRUE";
"B \NAC \NWC"14;
"S \NAC"
BN"0"135;
%"TAP"
"1","(0,1050)","0","standard","I50";
;
CDS_LIB"standard"
BODY_TYPE"PLUMBING"
HDL_TAP"TRUE";
"B \NAC \NWC"14;
"S \NAC"
BN"1"134;
%"TAP"
"1","(0,1100)","0","standard","I51";
;
CDS_LIB"standard"
BODY_TYPE"PLUMBING"
HDL_TAP"TRUE";
"B \NAC \NWC"14;
"S \NAC"
BN"2"133;
%"TAP"
"1","(0,1150)","0","standard","I52";
;
CDS_LIB"standard"
BODY_TYPE"PLUMBING"
HDL_TAP"TRUE";
"B \NAC \NWC"14;
"S \NAC"
BN"3"132;
%"TAP"
"1","(0,1200)","0","standard","I53";
;
CDS_LIB"standard"
BODY_TYPE"PLUMBING"
HDL_TAP"TRUE";
"B \NAC \NWC"14;
"S \NAC"
BN"4"131;
%"TAP"
"1","(0,1250)","0","standard","I54";
;
CDS_LIB"standard"
BODY_TYPE"PLUMBING"
HDL_TAP"TRUE";
"B \NAC \NWC"14;
"S \NAC"
BN"5"130;
%"TAP"
"1","(0,1300)","0","standard","I55";
;
CDS_LIB"standard"
BODY_TYPE"PLUMBING"
HDL_TAP"TRUE";
"B \NAC \NWC"14;
"S \NAC"
BN"6"129;
%"TAP"
"1","(0,1400)","0","standard","I56";
;
CDS_LIB"standard"
BODY_TYPE"PLUMBING"
HDL_TAP"TRUE";
"B \NAC \NWC"14;
"S \NAC"
BN"8"127;
%"TAP"
"1","(0,1350)","0","standard","I57";
;
CDS_LIB"standard"
BODY_TYPE"PLUMBING"
HDL_TAP"TRUE";
"B \NAC \NWC"14;
"S \NAC"
BN"7"128;
%"TAP"
"1","(0,1450)","0","standard","I58";
;
CDS_LIB"standard"
BODY_TYPE"PLUMBING"
HDL_TAP"TRUE";
"B \NAC \NWC"14;
"S \NAC"
BN"9"126;
%"TAP"
"1","(0,1500)","0","standard","I59";
;
CDS_LIB"standard"
BODY_TYPE"PLUMBING"
HDL_TAP"TRUE";
"B \NAC \NWC"14;
"S \NAC"
BN"10"125;
%"TAP"
"1","(0,1550)","0","standard","I60";
;
CDS_LIB"standard"
BODY_TYPE"PLUMBING"
HDL_TAP"TRUE";
"B \NAC \NWC"14;
"S \NAC"
BN"11"124;
%"TAP"
"1","(0,1650)","0","standard","I61";
;
CDS_LIB"standard"
BODY_TYPE"PLUMBING"
HDL_TAP"TRUE";
"B \NAC \NWC"14;
"S \NAC"
BN"13"122;
%"TAP"
"1","(0,1600)","0","standard","I62";
;
CDS_LIB"standard"
BODY_TYPE"PLUMBING"
HDL_TAP"TRUE";
"B \NAC \NWC"14;
"S \NAC"
BN"12"123;
%"TAP"
"1","(0,1800)","0","standard","I63";
;
CDS_LIB"standard"
BODY_TYPE"PLUMBING"
HDL_TAP"TRUE";
"B \NAC \NWC"14;
"S \NAC"
BN"16"119;
%"TAP"
"1","(0,1750)","0","standard","I64";
;
CDS_LIB"standard"
BODY_TYPE"PLUMBING"
HDL_TAP"TRUE";
"B \NAC \NWC"14;
"S \NAC"
BN"15"120;
%"TAP"
"1","(0,1700)","0","standard","I65";
;
CDS_LIB"standard"
BODY_TYPE"PLUMBING"
HDL_TAP"TRUE";
"B \NAC \NWC"14;
"S \NAC"
BN"14"121;
%"TAP"
"1","(0,1900)","0","standard","I66";
;
CDS_LIB"standard"
BODY_TYPE"PLUMBING"
HDL_TAP"TRUE";
"B \NAC \NWC"14;
"S \NAC"
BN"18"117;
%"TAP"
"1","(0,1850)","0","standard","I67";
;
CDS_LIB"standard"
BODY_TYPE"PLUMBING"
HDL_TAP"TRUE";
"B \NAC \NWC"14;
"S \NAC"
BN"17"118;
%"TAP"
"1","(0,1950)","0","standard","I68";
;
CDS_LIB"standard"
BODY_TYPE"PLUMBING"
HDL_TAP"TRUE";
"B \NAC \NWC"14;
"S \NAC"
BN"19"116;
%"TAP"
"1","(0,2050)","0","standard","I69";
;
CDS_LIB"standard"
BODY_TYPE"PLUMBING"
HDL_TAP"TRUE";
"B \NAC \NWC"14;
"S \NAC"
BN"21"114;
%"TAP"
"1","(0,2000)","0","standard","I70";
;
CDS_LIB"standard"
BODY_TYPE"PLUMBING"
HDL_TAP"TRUE";
"B \NAC \NWC"14;
"S \NAC"
BN"20"115;
%"TAP"
"1","(0,2150)","0","standard","I71";
;
CDS_LIB"standard"
BODY_TYPE"PLUMBING"
HDL_TAP"TRUE";
"B \NAC \NWC"14;
"S \NAC"
BN"23"112;
%"TAP"
"1","(0,2200)","0","standard","I72";
;
CDS_LIB"standard"
BODY_TYPE"PLUMBING"
HDL_TAP"TRUE";
"B \NAC \NWC"14;
"S \NAC"
BN"24"30;
%"TAP"
"1","(0,2100)","0","standard","I73";
;
CDS_LIB"standard"
BODY_TYPE"PLUMBING"
HDL_TAP"TRUE";
"B \NAC \NWC"14;
"S \NAC"
BN"22"113;
%"TAP"
"1","(0,2300)","0","standard","I74";
;
CDS_LIB"standard"
BODY_TYPE"PLUMBING"
HDL_TAP"TRUE";
"B \NAC \NWC"14;
"S \NAC"
BN"26"110;
%"TAP"
"1","(0,2250)","0","standard","I75";
;
CDS_LIB"standard"
BODY_TYPE"PLUMBING"
HDL_TAP"TRUE";
"B \NAC \NWC"14;
"S \NAC"
BN"25"111;
%"TAP"
"1","(0,2400)","0","standard","I76";
;
CDS_LIB"standard"
BODY_TYPE"PLUMBING"
HDL_TAP"TRUE";
"B \NAC \NWC"14;
"S \NAC"
BN"28"108;
%"TAP"
"1","(0,2450)","0","standard","I77";
;
CDS_LIB"standard"
BODY_TYPE"PLUMBING"
HDL_TAP"TRUE";
"B \NAC \NWC"14;
"S \NAC"
BN"29"107;
%"TAP"
"1","(0,2350)","0","standard","I78";
;
CDS_LIB"standard"
BODY_TYPE"PLUMBING"
HDL_TAP"TRUE";
"B \NAC \NWC"14;
"S \NAC"
BN"27"109;
%"TAP"
"1","(0,2550)","0","standard","I79";
;
CDS_LIB"standard"
BODY_TYPE"PLUMBING"
HDL_TAP"TRUE";
"B \NAC \NWC"14;
"S \NAC"
BN"31"105;
%"TAP"
"1","(0,2500)","0","standard","I80";
;
CDS_LIB"standard"
BODY_TYPE"PLUMBING"
HDL_TAP"TRUE";
"B \NAC \NWC"14;
"S \NAC"
BN"30"106;
%"TAP"
"1","(0,2650)","0","standard","I81";
;
CDS_LIB"standard"
BODY_TYPE"PLUMBING"
HDL_TAP"TRUE";
"B \NAC \NWC"15;
"S \NAC"
BN"0"104;
%"TAP"
"1","(0,2700)","0","standard","I82";
;
CDS_LIB"standard"
BODY_TYPE"PLUMBING"
HDL_TAP"TRUE";
"B \NAC \NWC"15;
"S \NAC"
BN"1"103;
%"TAP"
"1","(0,2750)","0","standard","I83";
;
CDS_LIB"standard"
BODY_TYPE"PLUMBING"
HDL_TAP"TRUE";
"B \NAC \NWC"15;
"S \NAC"
BN"2"102;
%"TAP"
"1","(0,2800)","0","standard","I84";
;
CDS_LIB"standard"
BODY_TYPE"PLUMBING"
HDL_TAP"TRUE";
"B \NAC \NWC"15;
"S \NAC"
BN"3"101;
%"TAP"
"1","(0,2950)","0","standard","I85";
;
CDS_LIB"standard"
BODY_TYPE"PLUMBING"
HDL_TAP"TRUE";
"B \NAC \NWC"15;
"S \NAC"
BN"6"98;
%"TAP"
"1","(0,2900)","0","standard","I86";
;
CDS_LIB"standard"
BODY_TYPE"PLUMBING"
HDL_TAP"TRUE";
"B \NAC \NWC"15;
"S \NAC"
BN"5"99;
%"TAP"
"1","(0,2850)","0","standard","I87";
;
CDS_LIB"standard"
BODY_TYPE"PLUMBING"
HDL_TAP"TRUE";
"B \NAC \NWC"15;
"S \NAC"
BN"4"100;
%"TAP"
"1","(0,3000)","0","standard","I88";
;
CDS_LIB"standard"
BODY_TYPE"PLUMBING"
HDL_TAP"TRUE";
"B \NAC \NWC"15;
"S \NAC"
BN"7"97;
%"TAP"
"1","(0,3050)","0","standard","I89";
;
CDS_LIB"standard"
BODY_TYPE"PLUMBING"
HDL_TAP"TRUE";
"B \NAC \NWC"15;
"S \NAC"
BN"8"96;
%"TAP"
"1","(0,3100)","0","standard","I90";
;
CDS_LIB"standard"
BODY_TYPE"PLUMBING"
HDL_TAP"TRUE";
"B \NAC \NWC"15;
"S \NAC"
BN"9"95;
%"TAP"
"1","(0,3150)","0","standard","I91";
;
CDS_LIB"standard"
BODY_TYPE"PLUMBING"
HDL_TAP"TRUE";
"B \NAC \NWC"15;
"S \NAC"
BN"10"94;
%"TAP"
"1","(0,3200)","0","standard","I92";
;
CDS_LIB"standard"
BODY_TYPE"PLUMBING"
HDL_TAP"TRUE";
"B \NAC \NWC"15;
"S \NAC"
BN"11"93;
%"TAP"
"1","(0,3300)","0","standard","I93";
;
CDS_LIB"standard"
BODY_TYPE"PLUMBING"
HDL_TAP"TRUE";
"B \NAC \NWC"15;
"S \NAC"
BN"13"91;
%"TAP"
"1","(0,3250)","0","standard","I94";
;
CDS_LIB"standard"
BODY_TYPE"PLUMBING"
HDL_TAP"TRUE";
"B \NAC \NWC"15;
"S \NAC"
BN"12"92;
%"TAP"
"1","(0,3350)","0","standard","I95";
;
CDS_LIB"standard"
BODY_TYPE"PLUMBING"
HDL_TAP"TRUE";
"B \NAC \NWC"15;
"S \NAC"
BN"14"90;
%"TAP"
"1","(0,3450)","0","standard","I96";
;
CDS_LIB"standard"
BODY_TYPE"PLUMBING"
HDL_TAP"TRUE";
"B \NAC \NWC"15;
"S \NAC"
BN"16"88;
%"TAP"
"1","(0,3400)","0","standard","I97";
;
CDS_LIB"standard"
BODY_TYPE"PLUMBING"
HDL_TAP"TRUE";
"B \NAC \NWC"15;
"S \NAC"
BN"15"89;
%"TAP"
"1","(0,3600)","0","standard","I98";
;
CDS_LIB"standard"
BODY_TYPE"PLUMBING"
HDL_TAP"TRUE";
"B \NAC \NWC"15;
"S \NAC"
BN"19"85;
%"TAP"
"1","(0,3500)","0","standard","I99";
;
CDS_LIB"standard"
BODY_TYPE"PLUMBING"
HDL_TAP"TRUE";
"B \NAC \NWC"15;
"S \NAC"
BN"17"87;
END.
